# S9S_MB_2U (Grand Teton) — schematic netlist excerpt (pin names and nets, part order shuffled) for the footprints in the layout excerpt that follows; sources: Cadence DE-HDL packaged netlist, KiCad conversion of 03242023_DA0F0TMBIJ0_F0T_Motherboard_J_brd_V01_OCP.brd

C999  Q_CAP  10UF 6.3V 20% X6S  pkg C0402  page 74 : A = PVCCIN_CPU0 ; B = GND
C2075  Q_CAP_DIFFBUS  DIFF BUS_0.22UF 6.3V 20% X6S  pkg C0201  page 181 : \1\ = P3E_PCH_NVS_TX_DP<0> ; \2\ = P3E_PCH_NVS_TX_C_DP<0>

(kicad_pcb
	(version 20260206)
	(generator "pcbnew")
	(generator_version "10.0")
	(general
		(thickness 1.6)
		(legacy_teardrops no)
	)
	(paper "A4")
	(title_block
		(title "03242023_DA0F0TMBIJ0_F0T_Motherboard_J_brd_V01_OCP.brd")
		(comment 1 "Grand Teton / footprints 1958-1959 of 6105")
	)
	(layers
		(0 "F.Cu" signal "TOP")
		(4 "In1.Cu" signal "GND")
		(6 "In2.Cu" signal "IN1")
		(8 "In3.Cu" signal "GND1")
		(10 "In4.Cu" signal "IN2")
		(12 "In5.Cu" signal "GND2")
		(14 "In6.Cu" signal "IN3")
		(16 "In7.Cu" signal "GND3")
		(18 "In8.Cu" signal "VCC")
		(20 "In9.Cu" signal "VCC1")
		(22 "In10.Cu" signal "GND4")
		(24 "In11.Cu" signal "IN4")
		(26 "In12.Cu" signal "GND5")
		(28 "In13.Cu" signal "IN5")
		(30 "In14.Cu" signal "GND6")
		(32 "In15.Cu" signal "IN6")
		(34 "In16.Cu" signal "GND7")
		(2 "B.Cu" signal "BOTTOM")
		(9 "F.Adhes" user "F.Adhesive")
		(11 "B.Adhes" user "B.Adhesive")
		(13 "F.Paste" user "Package Geometry/Pastemask Top")
		(15 "B.Paste" user "Package Geometry/Pastemask Bottom")
		(5 "F.SilkS" user "Ref Des/Silkscreen Top")
		(7 "B.SilkS" user "Ref Des/Silkscreen Bottom")
		(1 "F.Mask" user "Board Geometry/Soldermask Top")
		(3 "B.Mask" user "Board Geometry/Soldermask Bottom")
		(17 "Dwgs.User" user "User.Drawings")
		(19 "Cmts.User" user "User.Comments")
		(21 "Eco1.User" user "User.Eco1")
		(23 "Eco2.User" user "User.Eco2")
		(25 "Edge.Cuts" user "Board Geometry/Outline")
		(27 "Margin" user)
		(31 "F.CrtYd" user "Package Geometry/Place Bound Top")
		(29 "B.CrtYd" user "Package Geometry/Place Bound Bottom")
		(35 "F.Fab" user "Ref Des/Assembly Top")
		(33 "B.Fab" user "Ref Des/Assembly Bottom")
	)
	(footprint ""
		(layer "F.Cu")
		(at 353.254818 -244.03177 90)
		(property "Reference" "C999"
			(at 0 0 90)
			(layer "F.SilkS")
			(hide yes)
			(effects
				(font
					(size 1.27 1.27)
				)
			)
		)
		(property "Value" ""
			(at 0 0 90)
			(layer "F.Fab")
			(effects
				(font
					(size 1.27 1.27)
				)
			)
		)
		(duplicate_pad_numbers_are_jumpers no)
		(fp_line
			(start 0.7874 -0.4064)
			(end 0.7874 0.4064)
			(stroke
				(width 0.1524)
				(type default)
			)
			(layer "F.SilkS")
		)
		(fp_line
			(start -0.7874 -0.4064)
			(end 0.7874 -0.4064)
			(stroke
				(width 0.1524)
				(type default)
			)
			(layer "F.SilkS")
		)
		(fp_line
			(start 0.7874 0.4064)
			(end -0.7874 0.4064)
			(stroke
				(width 0.1524)
				(type default)
			)
			(layer "F.SilkS")
		)
		(fp_line
			(start -0.7874 0.4064)
			(end -0.7874 -0.4064)
			(stroke
				(width 0.1524)
				(type default)
			)
			(layer "F.SilkS")
		)
		(fp_line
			(start -0.12065 -0.305054)
			(end -0.12065 -0.2794)
			(stroke
				(width 0.1)
				(type default)
			)
			(layer "F.Fab")
		)
		(fp_line
			(start -0.67945 -0.305054)
			(end -0.12065 -0.305054)
			(stroke
				(width 0.1)
				(type default)
			)
			(layer "F.Fab")
		)
		(fp_line
			(start 0.67945 -0.3048)
			(end 0.67945 0.3048)
			(stroke
				(width 0.1)
				(type default)
			)
			(layer "F.Fab")
		)
		(fp_line
			(start 0.12065 -0.3048)
			(end 0.67945 -0.3048)
			(stroke
				(width 0.1)
				(type default)
			)
			(layer "F.Fab")
		)
		(fp_line
			(start 0.12065 -0.2794)
			(end 0.12065 -0.3048)
			(stroke
				(width 0.1)
				(type default)
			)
			(layer "F.Fab")
		)
		(fp_line
			(start -0.12065 -0.2794)
			(end 0.12065 -0.2794)
			(stroke
				(width 0.1)
				(type default)
			)
			(layer "F.Fab")
		)
		(fp_line
			(start 0.120396 0.2794)
			(end -0.12065 0.2794)
			(stroke
				(width 0.1)
				(type default)
			)
			(layer "F.Fab")
		)
		(fp_line
			(start -0.12065 0.2794)
			(end -0.12065 0.3048)
			(stroke
				(width 0.1)
				(type default)
			)
			(layer "F.Fab")
		)
		(fp_line
			(start 0.67945 0.3048)
			(end 0.120396 0.3048)
			(stroke
				(width 0.1)
				(type default)
			)
			(layer "F.Fab")
		)
		(fp_line
			(start 0.120396 0.3048)
			(end 0.120396 0.2794)
			(stroke
				(width 0.1)
				(type default)
			)
			(layer "F.Fab")
		)
		(fp_line
			(start -0.12065 0.3048)
			(end -0.67945 0.3048)
			(stroke
				(width 0.1)
				(type default)
			)
			(layer "F.Fab")
		)
		(fp_line
			(start -0.67945 0.3048)
			(end -0.67945 -0.305054)
			(stroke
				(width 0.1)
				(type default)
			)
			(layer "F.Fab")
		)
		(pad "1" smd circle
			(at -0.40005 0 90)
			(size 0 0)
			(layers "F.Cu" "F.Mask" "F.Paste")
			(net "PVCCIN_CPU0")
		)
		(pad "2" smd circle
			(at 0.40005 0 90)
			(size 0 0)
			(layers "F.Cu" "F.Mask" "F.Paste")
			(net "GND")
		)
	)
	(footprint ""
		(layer "F.Cu")
		(at 102.306374 -409.57754 90)
		(property "Reference" "C2075"
			(at 0 0 90)
			(layer "F.SilkS")
			(hide yes)
			(effects
				(font
					(size 1.27 1.27)
				)
			)
		)
		(property "Value" ""
			(at 0 0 90)
			(layer "F.Fab")
			(effects
				(font
					(size 1.27 1.27)
				)
			)
		)
		(duplicate_pad_numbers_are_jumpers no)
		(fp_line
			(start 0.299974 -0.150114)
			(end 0.299974 0.150114)
			(stroke
				(width 0.1)
				(type default)
			)
			(layer "F.Fab")
		)
		(fp_line
			(start -0.299974 -0.150114)
			(end 0.299974 -0.150114)
			(stroke
				(width 0.1)
				(type default)
			)
			(layer "F.Fab")
		)
		(fp_line
			(start 0.299974 0.150114)
			(end -0.299974 0.150114)
			(stroke
				(width 0.1)
				(type default)
			)
			(layer "F.Fab")
		)
		(fp_line
			(start -0.299974 0.150114)
			(end -0.299974 -0.150114)
			(stroke
				(width 0.1)
				(type default)
			)
			(layer "F.Fab")
		)
		(pad "1" smd rect
			(at -0.2667 0 90)
			(size 0.3048 0.381)
			(layers "F.Cu" "F.Mask" "F.Paste")
			(net "P3E_PCH_NVS_TX_DP<0>")
		)
		(pad "2" smd rect
			(at 0.2667 0 90)
			(size 0.3048 0.381)
			(layers "F.Cu" "F.Mask" "F.Paste")
			(net "P3E_PCH_NVS_TX_C_DP<0>")
		)
		(zone
			(layer "In1.Cu")
			(hatch none 0.5)
			(connect_pads
				(clearance 0)
			)
			(min_thickness 0.25)
			(keepout
				(tracks not_allowed)
				(vias allowed)
				(pads allowed)
				(copperpour not_allowed)
				(footprints allowed)
			)
			(placement
				(enabled no)
				(sheetname "")
			)
			(fill
				(thermal_gap 0.5)
				(thermal_bridge_width 0.5)
				(island_removal_mode 0)
			)
			(polygon
				(pts
					(arc
						(start 102.547674 -409.71724)
						(mid 102.525356 -409.663358)
						(end 102.471474 -409.64104)
					)
					(arc
						(start 102.141274 -409.64104)
						(mid 102.087392 -409.663358)
						(end 102.065074 -409.71724)
					)
					(arc
						(start 102.065074 -409.97124)
						(mid 102.087392 -410.025122)
						(end 102.141274 -410.04744)
					)
					(arc
						(start 102.471474 -410.04744)
						(mid 102.525356 -410.025122)
						(end 102.547674 -409.97124)
					)
				)
			)
		)
		(zone
			(layer "In1.Cu")
			(hatch none 0.5)
			(connect_pads
				(clearance 0)
			)
			(min_thickness 0.25)
			(keepout
				(tracks not_allowed)
				(vias allowed)
				(pads allowed)
				(copperpour not_allowed)
				(footprints allowed)
			)
			(placement
				(enabled no)
				(sheetname "")
			)
			(fill
				(thermal_gap 0.5)
				(thermal_bridge_width 0.5)
				(island_removal_mode 0)
			)
			(polygon
				(pts
					(arc
						(start 102.547674 -409.18384)
						(mid 102.525356 -409.129958)
						(end 102.471474 -409.10764)
					)
					(arc
						(start 102.141274 -409.10764)
						(mid 102.087392 -409.129958)
						(end 102.065074 -409.18384)
					)
					(arc
						(start 102.065074 -409.43784)
						(mid 102.087392 -409.491722)
						(end 102.141274 -409.51404)
					)
					(arc
						(start 102.471474 -409.51404)
						(mid 102.525356 -409.491722)
						(end 102.547674 -409.43784)
					)
				)
			)
		)
	)
)
